# S9S_MB_2U (Grand Teton) — schematic netlist excerpt (pin names and nets, part order shuffled) for the footprints in the layout excerpt that follows; sources: Cadence DE-HDL packaged netlist, KiCad conversion of 03242023_DA0F0TMBIJ0_F0T_Motherboard_J_brd_V01_OCP.brd

PR3962  Q_RES  15K 1% EMPTY  pkg 0402LF  page 192 : A = P12V_E1S_OV_0 ; B = GND
R2894  Q_RES  0 5% EMPTY  pkg 0402LF  page 234 : A = SMB_1_BMC_GPU_R_SDA ; B = SMB_1_BMC_GPU_BUF_R_SDA

(kicad_pcb
	(version 20260206)
	(generator "pcbnew")
	(generator_version "10.0")
	(general
		(thickness 1.6)
		(legacy_teardrops no)
	)
	(paper "A4")
	(title_block
		(title "03242023_DA0F0TMBIJ0_F0T_Motherboard_J_brd_V01_OCP.brd")
		(comment 1 "Grand Teton / footprints 1623-1624 of 6105")
	)
	(layers
		(0 "F.Cu" signal "TOP")
		(4 "In1.Cu" signal "GND")
		(6 "In2.Cu" signal "IN1")
		(8 "In3.Cu" signal "GND1")
		(10 "In4.Cu" signal "IN2")
		(12 "In5.Cu" signal "GND2")
		(14 "In6.Cu" signal "IN3")
		(16 "In7.Cu" signal "GND3")
		(18 "In8.Cu" signal "VCC")
		(20 "In9.Cu" signal "VCC1")
		(22 "In10.Cu" signal "GND4")
		(24 "In11.Cu" signal "IN4")
		(26 "In12.Cu" signal "GND5")
		(28 "In13.Cu" signal "IN5")
		(30 "In14.Cu" signal "GND6")
		(32 "In15.Cu" signal "IN6")
		(34 "In16.Cu" signal "GND7")
		(2 "B.Cu" signal "BOTTOM")
		(9 "F.Adhes" user "F.Adhesive")
		(11 "B.Adhes" user "B.Adhesive")
		(13 "F.Paste" user "Package Geometry/Pastemask Top")
		(15 "B.Paste" user "Package Geometry/Pastemask Bottom")
		(5 "F.SilkS" user "Ref Des/Silkscreen Top")
		(7 "B.SilkS" user "Ref Des/Silkscreen Bottom")
		(1 "F.Mask" user "Board Geometry/Soldermask Top")
		(3 "B.Mask" user "Board Geometry/Soldermask Bottom")
		(17 "Dwgs.User" user "User.Drawings")
		(19 "Cmts.User" user "User.Comments")
		(21 "Eco1.User" user "User.Eco1")
		(23 "Eco2.User" user "User.Eco2")
		(25 "Edge.Cuts" user "Board Geometry/Outline")
		(27 "Margin" user)
		(31 "F.CrtYd" user "Package Geometry/Place Bound Top")
		(29 "B.CrtYd" user "Package Geometry/Place Bound Bottom")
		(35 "F.Fab" user "Ref Des/Assembly Top")
		(33 "B.Fab" user "Ref Des/Assembly Bottom")
	)
	(footprint ""
		(layer "F.Cu")
		(at 249.28703 -44.979082 90)
		(property "Reference" "PR3962"
			(at 0 0 90)
			(layer "F.SilkS")
			(hide yes)
			(effects
				(font
					(size 1.27 1.27)
				)
			)
		)
		(property "Value" ""
			(at 0 0 90)
			(layer "F.Fab")
			(effects
				(font
					(size 1.27 1.27)
				)
			)
		)
		(duplicate_pad_numbers_are_jumpers no)
		(fp_line
			(start 0.7874 -0.4064)
			(end 0.7874 0.4064)
			(stroke
				(width 0.1524)
				(type default)
			)
			(layer "F.SilkS")
		)
		(fp_line
			(start -0.7874 -0.4064)
			(end 0.7874 -0.4064)
			(stroke
				(width 0.1524)
				(type default)
			)
			(layer "F.SilkS")
		)
		(fp_line
			(start 0.7874 0.4064)
			(end -0.7874 0.4064)
			(stroke
				(width 0.1524)
				(type default)
			)
			(layer "F.SilkS")
		)
		(fp_line
			(start -0.7874 0.4064)
			(end -0.7874 -0.4064)
			(stroke
				(width 0.1524)
				(type default)
			)
			(layer "F.SilkS")
		)
		(fp_line
			(start -0.12065 -0.305054)
			(end -0.12065 -0.2794)
			(stroke
				(width 0.1)
				(type default)
			)
			(layer "F.Fab")
		)
		(fp_line
			(start -0.67945 -0.305054)
			(end -0.12065 -0.305054)
			(stroke
				(width 0.1)
				(type default)
			)
			(layer "F.Fab")
		)
		(fp_line
			(start 0.67945 -0.3048)
			(end 0.67945 0.3048)
			(stroke
				(width 0.1)
				(type default)
			)
			(layer "F.Fab")
		)
		(fp_line
			(start 0.12065 -0.3048)
			(end 0.67945 -0.3048)
			(stroke
				(width 0.1)
				(type default)
			)
			(layer "F.Fab")
		)
		(fp_line
			(start 0.12065 -0.2794)
			(end 0.12065 -0.3048)
			(stroke
				(width 0.1)
				(type default)
			)
			(layer "F.Fab")
		)
		(fp_line
			(start -0.12065 -0.2794)
			(end 0.12065 -0.2794)
			(stroke
				(width 0.1)
				(type default)
			)
			(layer "F.Fab")
		)
		(fp_line
			(start 0.120396 0.2794)
			(end -0.12065 0.2794)
			(stroke
				(width 0.1)
				(type default)
			)
			(layer "F.Fab")
		)
		(fp_line
			(start -0.12065 0.2794)
			(end -0.12065 0.3048)
			(stroke
				(width 0.1)
				(type default)
			)
			(layer "F.Fab")
		)
		(fp_line
			(start 0.67945 0.3048)
			(end 0.120396 0.3048)
			(stroke
				(width 0.1)
				(type default)
			)
			(layer "F.Fab")
		)
		(fp_line
			(start 0.120396 0.3048)
			(end 0.120396 0.2794)
			(stroke
				(width 0.1)
				(type default)
			)
			(layer "F.Fab")
		)
		(fp_line
			(start -0.12065 0.3048)
			(end -0.67945 0.3048)
			(stroke
				(width 0.1)
				(type default)
			)
			(layer "F.Fab")
		)
		(fp_line
			(start -0.67945 0.3048)
			(end -0.67945 -0.305054)
			(stroke
				(width 0.1)
				(type default)
			)
			(layer "F.Fab")
		)
		(pad "1" smd circle
			(at -0.40005 0 90)
			(size 0 0)
			(layers "F.Cu" "F.Mask" "F.Paste")
			(net "P12V_E1S_OV_0")
		)
		(pad "2" smd circle
			(at 0.40005 0 90)
			(size 0 0)
			(layers "F.Cu" "F.Mask" "F.Paste")
			(net "GND")
		)
	)
	(footprint ""
		(layer "F.Cu")
		(at 50.98288 -434.812948 90)
		(property "Reference" "R2894"
			(at 0 0 90)
			(layer "F.SilkS")
			(hide yes)
			(effects
				(font
					(size 1.27 1.27)
				)
			)
		)
		(property "Value" ""
			(at 0 0 90)
			(layer "F.Fab")
			(effects
				(font
					(size 1.27 1.27)
				)
			)
		)
		(duplicate_pad_numbers_are_jumpers no)
		(fp_line
			(start 0.7874 -0.4064)
			(end 0.7874 0.4064)
			(stroke
				(width 0.1524)
				(type default)
			)
			(layer "F.SilkS")
		)
		(fp_line
			(start -0.7874 -0.4064)
			(end 0.7874 -0.4064)
			(stroke
				(width 0.1524)
				(type default)
			)
			(layer "F.SilkS")
		)
		(fp_line
			(start 0.7874 0.4064)
			(end -0.7874 0.4064)
			(stroke
				(width 0.1524)
				(type default)
			)
			(layer "F.SilkS")
		)
		(fp_line
			(start -0.7874 0.4064)
			(end -0.7874 -0.4064)
			(stroke
				(width 0.1524)
				(type default)
			)
			(layer "F.SilkS")
		)
		(fp_line
			(start -0.12065 -0.305054)
			(end -0.12065 -0.2794)
			(stroke
				(width 0.1)
				(type default)
			)
			(layer "F.Fab")
		)
		(fp_line
			(start -0.67945 -0.305054)
			(end -0.12065 -0.305054)
			(stroke
				(width 0.1)
				(type default)
			)
			(layer "F.Fab")
		)
		(fp_line
			(start 0.67945 -0.3048)
			(end 0.67945 0.3048)
			(stroke
				(width 0.1)
				(type default)
			)
			(layer "F.Fab")
		)
		(fp_line
			(start 0.12065 -0.3048)
			(end 0.67945 -0.3048)
			(stroke
				(width 0.1)
				(type default)
			)
			(layer "F.Fab")
		)
		(fp_line
			(start 0.12065 -0.2794)
			(end 0.12065 -0.3048)
			(stroke
				(width 0.1)
				(type default)
			)
			(layer "F.Fab")
		)
		(fp_line
			(start -0.12065 -0.2794)
			(end 0.12065 -0.2794)
			(stroke
				(width 0.1)
				(type default)
			)
			(layer "F.Fab")
		)
		(fp_line
			(start 0.120396 0.2794)
			(end -0.12065 0.2794)
			(stroke
				(width 0.1)
				(type default)
			)
			(layer "F.Fab")
		)
		(fp_line
			(start -0.12065 0.2794)
			(end -0.12065 0.3048)
			(stroke
				(width 0.1)
				(type default)
			)
			(layer "F.Fab")
		)
		(fp_line
			(start 0.67945 0.3048)
			(end 0.120396 0.3048)
			(stroke
				(width 0.1)
				(type default)
			)
			(layer "F.Fab")
		)
		(fp_line
			(start 0.120396 0.3048)
			(end 0.120396 0.2794)
			(stroke
				(width 0.1)
				(type default)
			)
			(layer "F.Fab")
		)
		(fp_line
			(start -0.12065 0.3048)
			(end -0.67945 0.3048)
			(stroke
				(width 0.1)
				(type default)
			)
			(layer "F.Fab")
		)
		(fp_line
			(start -0.67945 0.3048)
			(end -0.67945 -0.305054)
			(stroke
				(width 0.1)
				(type default)
			)
			(layer "F.Fab")
		)
		(pad "1" smd circle
			(at -0.40005 0 90)
			(size 0 0)
			(layers "F.Cu" "F.Mask" "F.Paste")
			(net "SMB_1_BMC_GPU_R_SDA")
		)
		(pad "2" smd circle
			(at 0.40005 0 90)
			(size 0 0)
			(layers "F.Cu" "F.Mask" "F.Paste")
			(net "SMB_1_BMC_GPU_BUF_R_SDA")
		)
	)
)
